# T6G (Grand Teton) — schematic netlist excerpt (pin names and nets, part order shuffled) for the footprints in the layout excerpt that follows; sources: Cadence DE-HDL packaged netlist, KiCad conversion of 04192023_DAF0TMB3IC0_F0TG_MB_C_brd_V02_OCP.brd

R683  Q_RES  33.2 1% CHIP  pkg 0201LF  page 300 : A = SMB_RT_CPU0_P2_ROM_R_SDA ; B = SMB_RT_CPU0_P2_ROM_SDA
R8092  Q_RES  10K 5% EMPTY  pkg 0402LF  page 136 : A = P3V3_OCP_SFF_R ; B = OCP_V3_1_P3V3_R1_PWRGD
PC6640  Q_CAP  100NF 50V 10% X7R  pkg C0402  page 365 : A = SW_P0V9_RETIMER_CPU1_BOOT2_RC ; B = SW_P0V9_RETIMER_CPU1_PH2

(kicad_pcb
	(version 20260206)
	(generator "pcbnew")
	(generator_version "10.0")
	(general
		(thickness 1.6)
		(legacy_teardrops no)
	)
	(paper "A4")
	(title_block
		(title "04192023_DAF0TMB3IC0_F0TG_MB_C_brd_V02_OCP.brd")
		(comment 1 "Grand Teton / footprints 518-520 of 8354")
	)
	(layers
		(0 "F.Cu" signal "TOP")
		(4 "In1.Cu" signal "GND")
		(6 "In2.Cu" signal "IN1")
		(8 "In3.Cu" signal "GND1")
		(10 "In4.Cu" signal "IN2")
		(12 "In5.Cu" signal "GND2")
		(14 "In6.Cu" signal "IN3")
		(16 "In7.Cu" signal "GND3")
		(18 "In8.Cu" signal "VCC")
		(20 "In9.Cu" signal "VCC1")
		(22 "In10.Cu" signal "GND4")
		(24 "In11.Cu" signal "IN4")
		(26 "In12.Cu" signal "GND5")
		(28 "In13.Cu" signal "IN5")
		(30 "In14.Cu" signal "GND6")
		(32 "In15.Cu" signal "IN6")
		(34 "In16.Cu" signal "GND7")
		(2 "B.Cu" signal "BOTTOM")
		(9 "F.Adhes" user "F.Adhesive")
		(11 "B.Adhes" user "B.Adhesive")
		(13 "F.Paste" user "Package Geometry/Pastemask Top")
		(15 "B.Paste" user "Package Geometry/Pastemask Bottom")
		(5 "F.SilkS" user "Ref Des/Silkscreen Top")
		(7 "B.SilkS" user "Ref Des/Silkscreen Bottom")
		(1 "F.Mask" user "Board Geometry/Soldermask Top")
		(3 "B.Mask" user "Board Geometry/Soldermask Bottom")
		(17 "Dwgs.User" user "User.Drawings")
		(19 "Cmts.User" user "User.Comments")
		(21 "Eco1.User" user "User.Eco1")
		(23 "Eco2.User" user "User.Eco2")
		(25 "Edge.Cuts" user "Board Geometry/Outline")
		(27 "Margin" user)
		(31 "F.CrtYd" user "Package Geometry/Place Bound Top")
		(29 "B.CrtYd" user "Package Geometry/Place Bound Bottom")
		(35 "F.Fab" user "Ref Des/Assembly Top")
		(33 "B.Fab" user "Ref Des/Assembly Bottom")
	)
	(footprint ""
		(layer "F.Cu")
		(at 27.561794 -393.317984 -90)
		(property "Reference" "PC6640"
			(at 0 0 270)
			(layer "F.SilkS")
			(hide yes)
			(effects
				(font
					(size 1.27 1.27)
				)
			)
		)
		(property "Value" ""
			(at 0 0 270)
			(layer "F.Fab")
			(effects
				(font
					(size 1.27 1.27)
				)
			)
		)
		(duplicate_pad_numbers_are_jumpers no)
		(fp_line
			(start -0.7874 0.4064)
			(end -0.7874 -0.4064)
			(stroke
				(width 0.1524)
				(type default)
			)
			(layer "F.SilkS")
		)
		(fp_line
			(start 0.7874 0.4064)
			(end -0.7874 0.4064)
			(stroke
				(width 0.1524)
				(type default)
			)
			(layer "F.SilkS")
		)
		(fp_line
			(start -0.7874 -0.4064)
			(end 0.7874 -0.4064)
			(stroke
				(width 0.1524)
				(type default)
			)
			(layer "F.SilkS")
		)
		(fp_line
			(start 0.7874 -0.4064)
			(end 0.7874 0.4064)
			(stroke
				(width 0.1524)
				(type default)
			)
			(layer "F.SilkS")
		)
		(fp_line
			(start -0.67945 0.3048)
			(end -0.67945 -0.305054)
			(stroke
				(width 0.1)
				(type default)
			)
			(layer "F.Fab")
		)
		(fp_line
			(start -0.12065 0.3048)
			(end -0.67945 0.3048)
			(stroke
				(width 0.1)
				(type default)
			)
			(layer "F.Fab")
		)
		(fp_line
			(start 0.120396 0.3048)
			(end 0.120396 0.2794)
			(stroke
				(width 0.1)
				(type default)
			)
			(layer "F.Fab")
		)
		(fp_line
			(start 0.67945 0.3048)
			(end 0.120396 0.3048)
			(stroke
				(width 0.1)
				(type default)
			)
			(layer "F.Fab")
		)
		(fp_line
			(start -0.12065 0.2794)
			(end -0.12065 0.3048)
			(stroke
				(width 0.1)
				(type default)
			)
			(layer "F.Fab")
		)
		(fp_line
			(start 0.120396 0.2794)
			(end -0.12065 0.2794)
			(stroke
				(width 0.1)
				(type default)
			)
			(layer "F.Fab")
		)
		(fp_line
			(start -0.12065 -0.2794)
			(end 0.12065 -0.2794)
			(stroke
				(width 0.1)
				(type default)
			)
			(layer "F.Fab")
		)
		(fp_line
			(start 0.12065 -0.2794)
			(end 0.12065 -0.3048)
			(stroke
				(width 0.1)
				(type default)
			)
			(layer "F.Fab")
		)
		(fp_line
			(start 0.12065 -0.3048)
			(end 0.67945 -0.3048)
			(stroke
				(width 0.1)
				(type default)
			)
			(layer "F.Fab")
		)
		(fp_line
			(start 0.67945 -0.3048)
			(end 0.67945 0.3048)
			(stroke
				(width 0.1)
				(type default)
			)
			(layer "F.Fab")
		)
		(fp_line
			(start -0.67945 -0.305054)
			(end -0.12065 -0.305054)
			(stroke
				(width 0.1)
				(type default)
			)
			(layer "F.Fab")
		)
		(fp_line
			(start -0.12065 -0.305054)
			(end -0.12065 -0.2794)
			(stroke
				(width 0.1)
				(type default)
			)
			(layer "F.Fab")
		)
		(pad "1" smd circle
			(at -0.40005 0 270)
			(size 0 0)
			(layers "F.Cu" "F.Mask" "F.Paste")
			(net "SW_P0V9_RETIMER_CPU1_BOOT2_RC")
		)
		(pad "2" smd circle
			(at 0.40005 0 270)
			(size 0 0)
			(layers "F.Cu" "F.Mask" "F.Paste")
			(net "SW_P0V9_RETIMER_CPU1_PH2")
		)
	)
	(footprint ""
		(layer "F.Cu")
		(at 419.391084 -423.777664 90)
		(property "Reference" "R683"
			(at 0 0 90)
			(layer "F.SilkS")
			(hide yes)
			(effects
				(font
					(size 1.27 1.27)
				)
			)
		)
		(property "Value" ""
			(at 0 0 90)
			(layer "F.Fab")
			(effects
				(font
					(size 1.27 1.27)
				)
			)
		)
		(duplicate_pad_numbers_are_jumpers no)
		(fp_line
			(start 0.32512 -0.175006)
			(end 0.32512 0.175006)
			(stroke
				(width 0.1)
				(type default)
			)
			(layer "F.Fab")
		)
		(fp_line
			(start -0.32512 -0.175006)
			(end 0.32512 -0.175006)
			(stroke
				(width 0.1)
				(type default)
			)
			(layer "F.Fab")
		)
		(fp_line
			(start 0.32512 0.175006)
			(end -0.32512 0.175006)
			(stroke
				(width 0.1)
				(type default)
			)
			(layer "F.Fab")
		)
		(fp_line
			(start -0.32512 0.175006)
			(end -0.32512 -0.175006)
			(stroke
				(width 0.1)
				(type default)
			)
			(layer "F.Fab")
		)
		(pad "1" smd rect
			(at -0.2667 0 90)
			(size 0.3048 0.381)
			(layers "F.Cu" "F.Mask" "F.Paste")
			(net "SMB_RT_CPU0_P2_ROM_R_SDA")
		)
		(pad "2" smd rect
			(at 0.2667 0 270)
			(size 0.3048 0.381)
			(layers "F.Cu" "F.Mask" "F.Paste")
			(net "SMB_RT_CPU0_P2_ROM_SDA")
		)
	)
	(footprint ""
		(layer "F.Cu")
		(at 413.766 -98.425 90)
		(property "Reference" "R8092"
			(at 0 0 90)
			(layer "F.SilkS")
			(hide yes)
			(effects
				(font
					(size 1.27 1.27)
				)
			)
		)
		(property "Value" ""
			(at 0 0 90)
			(layer "F.Fab")
			(effects
				(font
					(size 1.27 1.27)
				)
			)
		)
		(duplicate_pad_numbers_are_jumpers no)
		(fp_line
			(start 0.7874 -0.4064)
			(end 0.7874 0.4064)
			(stroke
				(width 0.1524)
				(type default)
			)
			(layer "F.SilkS")
		)
		(fp_line
			(start -0.7874 -0.4064)
			(end 0.7874 -0.4064)
			(stroke
				(width 0.1524)
				(type default)
			)
			(layer "F.SilkS")
		)
		(fp_line
			(start 0.7874 0.4064)
			(end -0.7874 0.4064)
			(stroke
				(width 0.1524)
				(type default)
			)
			(layer "F.SilkS")
		)
		(fp_line
			(start -0.7874 0.4064)
			(end -0.7874 -0.4064)
			(stroke
				(width 0.1524)
				(type default)
			)
			(layer "F.SilkS")
		)
		(fp_line
			(start -0.12065 -0.305054)
			(end -0.12065 -0.2794)
			(stroke
				(width 0.1)
				(type default)
			)
			(layer "F.Fab")
		)
		(fp_line
			(start -0.67945 -0.305054)
			(end -0.12065 -0.305054)
			(stroke
				(width 0.1)
				(type default)
			)
			(layer "F.Fab")
		)
		(fp_line
			(start 0.67945 -0.3048)
			(end 0.67945 0.3048)
			(stroke
				(width 0.1)
				(type default)
			)
			(layer "F.Fab")
		)
		(fp_line
			(start 0.12065 -0.3048)
			(end 0.67945 -0.3048)
			(stroke
				(width 0.1)
				(type default)
			)
			(layer "F.Fab")
		)
		(fp_line
			(start 0.12065 -0.2794)
			(end 0.12065 -0.3048)
			(stroke
				(width 0.1)
				(type default)
			)
			(layer "F.Fab")
		)
		(fp_line
			(start -0.12065 -0.2794)
			(end 0.12065 -0.2794)
			(stroke
				(width 0.1)
				(type default)
			)
			(layer "F.Fab")
		)
		(fp_line
			(start 0.120396 0.2794)
			(end -0.12065 0.2794)
			(stroke
				(width 0.1)
				(type default)
			)
			(layer "F.Fab")
		)
		(fp_line
			(start -0.12065 0.2794)
			(end -0.12065 0.3048)
			(stroke
				(width 0.1)
				(type default)
			)
			(layer "F.Fab")
		)
		(fp_line
			(start 0.67945 0.3048)
			(end 0.120396 0.3048)
			(stroke
				(width 0.1)
				(type default)
			)
			(layer "F.Fab")
		)
		(fp_line
			(start 0.120396 0.3048)
			(end 0.120396 0.2794)
			(stroke
				(width 0.1)
				(type default)
			)
			(layer "F.Fab")
		)
		(fp_line
			(start -0.12065 0.3048)
			(end -0.67945 0.3048)
			(stroke
				(width 0.1)
				(type default)
			)
			(layer "F.Fab")
		)
		(fp_line
			(start -0.67945 0.3048)
			(end -0.67945 -0.305054)
			(stroke
				(width 0.1)
				(type default)
			)
			(layer "F.Fab")
		)
		(pad "1" smd circle
			(at -0.40005 0 90)
			(size 0 0)
			(layers "F.Cu" "F.Mask" "F.Paste")
			(net "P3V3_OCP_SFF_R")
		)
		(pad "2" smd circle
			(at 0.40005 0 90)
			(size 0 0)
			(layers "F.Cu" "F.Mask" "F.Paste")
			(net "OCP_V3_1_P3V3_R1_PWRGD")
		)
	)
)
